(kicad_pcb
	(version 20260206)
	(generator "pcbnew")
	(generator_version "10.0")
	(general
		(thickness 1.6)
		(legacy_teardrops no)
	)
	(paper "A4")
	(title_block
		(title "03242023_DA0F0TMBIJ0_F0T_Motherboard_J_brd_V01_OCP.brd")
		(comment 1 "Grand Teton / footprint 3039 of 6105 (U2), pads 855-956 of 4677")
	)
	(layers
		(0 "F.Cu" signal "TOP")
		(4 "In1.Cu" signal "GND")
		(6 "In2.Cu" signal "IN1")
		(8 "In3.Cu" signal "GND1")
		(10 "In4.Cu" signal "IN2")
		(12 "In5.Cu" signal "GND2")
		(14 "In6.Cu" signal "IN3")
		(16 "In7.Cu" signal "GND3")
		(18 "In8.Cu" signal "VCC")
		(20 "In9.Cu" signal "VCC1")
		(22 "In10.Cu" signal "GND4")
		(24 "In11.Cu" signal "IN4")
		(26 "In12.Cu" signal "GND5")
		(28 "In13.Cu" signal "IN5")
		(30 "In14.Cu" signal "GND6")
		(32 "In15.Cu" signal "IN6")
		(34 "In16.Cu" signal "GND7")
		(2 "B.Cu" signal "BOTTOM")
		(9 "F.Adhes" user "F.Adhesive")
		(11 "B.Adhes" user "B.Adhesive")
		(13 "F.Paste" user "Package Geometry/Pastemask Top")
		(15 "B.Paste" user "Package Geometry/Pastemask Bottom")
		(5 "F.SilkS" user "Ref Des/Silkscreen Top")
		(7 "B.SilkS" user "Ref Des/Silkscreen Bottom")
		(1 "F.Mask" user "Board Geometry/Soldermask Top")
		(3 "B.Mask" user "Board Geometry/Soldermask Bottom")
		(17 "Dwgs.User" user "User.Drawings")
		(19 "Cmts.User" user "User.Comments")
		(21 "Eco1.User" user "User.Eco1")
		(23 "Eco2.User" user "User.Eco2")
		(25 "Edge.Cuts" user "Board Geometry/Outline")
		(27 "Margin" user)
		(31 "F.CrtYd" user "Package Geometry/Place Bound Top")
		(29 "B.CrtYd" user "Package Geometry/Place Bound Bottom")
		(35 "F.Fab" user "Ref Des/Assembly Top")
		(33 "B.Fab" user "Ref Des/Assembly Bottom")
	)
	(footprint ""
		(layer "F.Cu")
		(at 359.870248 -251.76988 90)
		(property "Reference" "U2"
			(at -74.416158 -44.488608 0)
			(unlocked yes)
			(layer "F.SilkS")
			(effects
				(font
					(size 1.6002 1.1938)
					(thickness 0.1524)
				)
				(justify left)
			)
		)
		(property "Value" ""
			(at 0 0 90)
			(layer "F.Fab")
			(effects
				(font
					(size 1.27 1.27)
				)
			)
		)
		(duplicate_pad_numbers_are_jumpers no)
		(pad "AW70" smd circle
			(at 20.333462 -9.107932 270)
			(size 0.4318 0.4318)
			(layers "F.Cu" "F.Mask" "F.Paste")
			(net "FM_S3M_CPU0_LVC1_GPIO_4")
		)
		(pad "AW72" smd circle
			(at 21.961094 -9.107932 270)
			(size 0.4318 0.4318)
			(layers "F.Cu" "F.Mask" "F.Paste")
			(net "GND")
		)
		(pad "AW74" smd circle
			(at 23.58898 -9.107932 270)
			(size 0.4318 0.4318)
			(layers "F.Cu" "F.Mask" "F.Paste")
			(net "UPI_CPU1_CPU0_P2P2_DP<7>")
		)
		(pad "AW76" smd circle
			(at 25.216612 -9.107932 270)
			(size 0.4318 0.4318)
			(layers "F.Cu" "F.Mask" "F.Paste")
			(net "PVCCFA_EHV_FIVRA_CPU0")
		)
		(pad "AW78" smd circle
			(at 26.844498 -9.107932 270)
			(size 0.4318 0.4318)
			(layers "F.Cu" "F.Mask" "F.Paste")
			(net "UPI_CPU0_CPU1_P2P2_DN<13>")
		)
		(pad "AW80" smd circle
			(at 28.472384 -9.107932 270)
			(size 0.4318 0.4318)
			(layers "F.Cu" "F.Mask" "F.Paste")
			(net "GND")
		)
		(pad "AW82" smd circle
			(at 30.100016 -9.107932 270)
			(size 0.4318 0.4318)
			(layers "F.Cu" "F.Mask" "F.Paste")
			(net "GND")
		)
		(pad "AW84" smd circle
			(at 31.727902 -9.107932 270)
			(size 0.4318 0.4318)
			(layers "F.Cu" "F.Mask" "F.Paste")
			(net "GND")
		)
		(pad "AW86" smd circle
			(at 33.355534 -9.107932 270)
			(size 0.4318 0.4318)
			(layers "F.Cu" "F.Mask" "F.Paste")
			(net "P5E_CPU0_PE4_TX_DN<14>")
		)
		(pad "AW88" smd circle
			(at 34.98342 -9.107932 270)
			(size 0.4318 0.4318)
			(layers "F.Cu" "F.Mask" "F.Paste")
			(net "GND")
		)
		(pad "AW90" smd circle
			(at 36.611306 -9.107932 270)
			(size 0.4318 0.4318)
			(layers "F.Cu" "F.Mask" "F.Paste")
			(net "P5E_CPU0_PE4_RX_DP<14>")
		)
		(pad "AY2" smd circle
			(at -36.611306 -8.748268 270)
			(size 0.4318 0.4318)
			(layers "F.Cu" "F.Mask" "F.Paste")
			(net "UPI_CPU0_CPU1_P0P1_DP<15>")
		)
		(pad "AY4" smd circle
			(at -34.98342 -8.748268 270)
			(size 0.4318 0.4318)
			(layers "F.Cu" "F.Mask" "F.Paste")
			(net "GND")
		)
		(pad "AY6" smd circle
			(at -33.355534 -8.748268 270)
			(size 0.4318 0.4318)
			(layers "F.Cu" "F.Mask" "F.Paste")
			(net "UPI_CPU1_CPU0_P1P0_DN<15>")
		)
		(pad "AY8" smd circle
			(at -31.727902 -8.748268 270)
			(size 0.4318 0.4318)
			(layers "F.Cu" "F.Mask" "F.Paste")
			(net "GND")
		)
		(pad "AY10" smd circle
			(at -30.100016 -8.748268 270)
			(size 0.4318 0.4318)
			(layers "F.Cu" "F.Mask" "F.Paste")
			(net "P5E_CPU0_PE0_RX_DP<15>")
		)
		(pad "AY12" smd circle
			(at -28.472384 -8.748268 270)
			(size 0.4318 0.4318)
			(layers "F.Cu" "F.Mask" "F.Paste")
			(net "GND")
		)
		(pad "AY14" smd circle
			(at -26.844498 -8.748268 270)
			(size 0.4318 0.4318)
			(layers "F.Cu" "F.Mask" "F.Paste")
			(net "P5E_CPU0_PE0_TX_DP<14>")
		)
		(pad "AY16" smd circle
			(at -25.216612 -8.748268 270)
			(size 0.4318 0.4318)
			(layers "F.Cu" "F.Mask" "F.Paste")
			(net "GND")
		)
		(pad "AY18" smd circle
			(at -23.58898 -8.748268 270)
			(size 0.4318 0.4318)
			(layers "F.Cu" "F.Mask" "F.Paste")
			(net "PVCCINFAON_CPU0")
		)
		(pad "AY20" smd circle
			(at -21.961094 -8.748268 270)
			(size 0.4318 0.4318)
			(layers "F.Cu" "F.Mask" "F.Paste")
			(net "PU_TAP_ODT_CPU0_EN")
		)
		(pad "AY22" smd circle
			(at -20.333462 -8.748268 270)
			(size 0.4318 0.4318)
			(layers "F.Cu" "F.Mask" "F.Paste")
			(net "H_CPU0_ERR1_LVC1_R_N")
		)
		(pad "AY24" smd circle
			(at -18.705576 -8.748268 270)
			(size 0.4318 0.4318)
			(layers "F.Cu" "F.Mask" "F.Paste")
			(net "NC_CPU0_SOC_SPARE0")
		)
		(pad "AY26" smd circle
			(at -17.07769 -8.748268 270)
			(size 0.4318 0.4318)
			(layers "F.Cu" "F.Mask" "F.Paste")
			(net "NC_CPU0_VIEWPIN_DIE00<0>")
		)
		(pad "AY61" smd circle
			(at 13.008356 -8.638286 270)
			(size 0.4318 0.4318)
			(layers "F.Cu" "F.Mask" "F.Paste")
			(net "TP_SPI_IBL_CPU0_TPM_IO1")
		)
		(pad "AY63" smd circle
			(at 14.635988 -8.638286 270)
			(size 0.4318 0.4318)
			(layers "F.Cu" "F.Mask" "F.Paste")
			(net "FM_CPU0_PKGID1")
		)
		(pad "AY65" smd circle
			(at 16.263874 -8.638286 270)
			(size 0.4318 0.4318)
			(layers "F.Cu" "F.Mask" "F.Paste")
			(net "NC_CPU0_VIEWPIN_DIE01<2>")
		)
		(pad "AY67" smd circle
			(at 17.89176 -8.638286 270)
			(size 0.4318 0.4318)
			(layers "F.Cu" "F.Mask" "F.Paste")
			(net "TP_SPI_IBL_CPU0_TPM_CS0_N")
		)
		(pad "AY69" smd circle
			(at 19.519392 -8.638286 270)
			(size 0.4318 0.4318)
			(layers "F.Cu" "F.Mask" "F.Paste")
			(net "FM_S3M_CPU0_LVC1_GPIO_3")
		)
		(pad "AY71" smd circle
			(at 21.147278 -8.638286 270)
			(size 0.4318 0.4318)
			(layers "F.Cu" "F.Mask" "F.Paste")
			(net "GND")
		)
		(pad "AY73" smd circle
			(at 22.77491 -8.638286 270)
			(size 0.4318 0.4318)
			(layers "F.Cu" "F.Mask" "F.Paste")
			(net "UPI_CPU1_CPU0_P2P2_DP<10>")
		)
		(pad "AY75" smd circle
			(at 24.402796 -8.638286 270)
			(size 0.4318 0.4318)
			(layers "F.Cu" "F.Mask" "F.Paste")
			(net "UPI_CPU1_CPU0_P2P2_DN<9>")
		)
		(pad "AY77" smd circle
			(at 26.030682 -8.638286 270)
			(size 0.4318 0.4318)
			(layers "F.Cu" "F.Mask" "F.Paste")
			(net "GND")
		)
		(pad "AY79" smd circle
			(at 27.658314 -8.638286 270)
			(size 0.4318 0.4318)
			(layers "F.Cu" "F.Mask" "F.Paste")
			(net "GND")
		)
		(pad "AY81" smd circle
			(at 29.2862 -8.638286 270)
			(size 0.4318 0.4318)
			(layers "F.Cu" "F.Mask" "F.Paste")
			(net "GND")
		)
		(pad "AY83" smd circle
			(at 30.914086 -8.638286 270)
			(size 0.4318 0.4318)
			(layers "F.Cu" "F.Mask" "F.Paste")
			(net "GND")
		)
		(pad "AY85" smd circle
			(at 32.541718 -8.638286 270)
			(size 0.4318 0.4318)
			(layers "F.Cu" "F.Mask" "F.Paste")
			(net "VSENSE_PVCCFA_EHV_FIVRA_CPU0_DP")
		)
		(pad "AY87" smd circle
			(at 34.169604 -8.638286 270)
			(size 0.4318 0.4318)
			(layers "F.Cu" "F.Mask" "F.Paste")
			(net "P5E_CPU0_PE4_TX_DP<14>")
		)
		(pad "AY89" smd circle
			(at 35.797236 -8.638286 270)
			(size 0.4318 0.4318)
			(layers "F.Cu" "F.Mask" "F.Paste")
			(net "PVCCFA_EHV_FIVRA_CPU0")
		)
		(pad "AY91" smd oval
			(at 37.425122 -8.638286)
			(size 0.381 0.4826)
			(drill
				(offset 0 -0.0508)
			)
			(layers "F.Cu" "F.Mask" "F.Paste")
			(net "P5E_CPU0_PE4_RX_DN<14>")
		)
		(pad "B6" smd oval
			(at -33.355534 -26.604468 135)
			(size 0.381 0.4826)
			(drill
				(offset 0 -0.0508)
			)
			(layers "F.Cu" "F.Mask" "F.Paste")
			(net "GND")
		)
		(pad "B8" smd oval
			(at -31.727902 -26.604468 135)
			(size 0.381 0.4826)
			(drill
				(offset 0 -0.0508)
			)
			(layers "F.Cu" "F.Mask" "F.Paste")
			(net "M_A_CPU0_SB_DQ<28>")
		)
		(pad "B10" smd oval
			(at -30.100016 -26.604468 90)
			(size 0.381 0.4826)
			(drill
				(offset 0 -0.0508)
			)
			(layers "F.Cu" "F.Mask" "F.Paste")
			(net "M_A_CPU0_SB_DQ<25>")
		)
		(pad "B12" smd circle
			(at -28.472384 -26.604468 270)
			(size 0.4318 0.4318)
			(layers "F.Cu" "F.Mask" "F.Paste")
			(net "GND")
		)
		(pad "B14" smd circle
			(at -26.844498 -26.604468 270)
			(size 0.4318 0.4318)
			(layers "F.Cu" "F.Mask" "F.Paste")
			(net "M_B_CPU0_SB_DQ<30>")
		)
		(pad "B16" smd circle
			(at -25.216612 -26.604468 270)
			(size 0.4318 0.4318)
			(layers "F.Cu" "F.Mask" "F.Paste")
			(net "M_B_CPU0_SB_DQ<25>")
		)
		(pad "B18" smd circle
			(at -23.58898 -26.604468 270)
			(size 0.4318 0.4318)
			(layers "F.Cu" "F.Mask" "F.Paste")
			(net "GND")
		)
		(pad "B20" smd circle
			(at -21.961094 -26.604468 270)
			(size 0.4318 0.4318)
			(layers "F.Cu" "F.Mask" "F.Paste")
			(net "M_A_CPU0_SB_DQ<20>")
		)
		(pad "B22" smd circle
			(at -20.333462 -26.604468 270)
			(size 0.4318 0.4318)
			(layers "F.Cu" "F.Mask" "F.Paste")
			(net "M_A_CPU0_SB_DQ<17>")
		)
		(pad "B24" smd circle
			(at -18.705576 -26.604468 270)
			(size 0.4318 0.4318)
			(layers "F.Cu" "F.Mask" "F.Paste")
			(net "GND")
		)
		(pad "B26" smd circle
			(at -17.07769 -26.604468 270)
			(size 0.4318 0.4318)
			(layers "F.Cu" "F.Mask" "F.Paste")
			(net "M_A_CPU0_SB_DQ<12>")
		)
		(pad "B28" smd circle
			(at -15.450058 -26.604468 270)
			(size 0.4318 0.4318)
			(layers "F.Cu" "F.Mask" "F.Paste")
			(net "M_A_CPU0_SB_DQ<9>")
		)
		(pad "B30" smd circle
			(at -13.822426 -26.604468 270)
			(size 0.4318 0.4318)
			(layers "F.Cu" "F.Mask" "F.Paste")
			(net "GND")
		)
		(pad "B32" smd circle
			(at -12.19454 -26.604468 270)
			(size 0.4318 0.4318)
			(layers "F.Cu" "F.Mask" "F.Paste")
			(net "M_A_CPU0_SB_CB<0>")
		)
		(pad "B34" smd circle
			(at -10.566654 -26.604468 270)
			(size 0.4318 0.4318)
			(layers "F.Cu" "F.Mask" "F.Paste")
			(net "M_A_CPU0_SB_CB<5>")
		)
		(pad "B36" smd circle
			(at -8.939022 -26.604468 270)
			(size 0.4318 0.4318)
			(layers "F.Cu" "F.Mask" "F.Paste")
			(net "GND")
		)
		(pad "B38" smd circle
			(at -7.311136 -26.604468 270)
			(size 0.4318 0.4318)
			(layers "F.Cu" "F.Mask" "F.Paste")
			(net "M_A_CPU0_SB_CS_N<0>")
		)
		(pad "B40" smd circle
			(at -5.68325 -26.604468 270)
			(size 0.4318 0.4318)
			(layers "F.Cu" "F.Mask" "F.Paste")
			(net "M_A_CPU0_SB_CA<4>")
		)
		(pad "B42" smd circle
			(at -4.055618 -26.604468 270)
			(size 0.4318 0.4318)
			(layers "F.Cu" "F.Mask" "F.Paste")
			(net "GND")
		)
		(pad "B44" smd oval
			(at -2.427732 -26.604468 45)
			(size 0.381 0.4826)
			(drill
				(offset 0 -0.0508)
			)
			(layers "F.Cu" "F.Mask" "F.Paste")
			(net "M_A_CPU0_CLK_DN<0>")
		)
		(pad "B49" smd oval
			(at 3.241802 -26.494486 135)
			(size 0.381 0.4826)
			(drill
				(offset 0 -0.0508)
			)
			(layers "F.Cu" "F.Mask" "F.Paste")
			(net "GND")
		)
		(pad "B51" smd circle
			(at 4.869434 -26.494486 270)
			(size 0.4318 0.4318)
			(layers "F.Cu" "F.Mask" "F.Paste")
			(net "M_A_CPU0_SA_CA<2>")
		)
		(pad "B53" smd circle
			(at 6.49732 -26.494486 270)
			(size 0.4318 0.4318)
			(layers "F.Cu" "F.Mask" "F.Paste")
			(net "M_A_CPU0_SA_CS_N<1>")
		)
		(pad "B55" smd circle
			(at 8.124952 -26.494486 270)
			(size 0.4318 0.4318)
			(layers "F.Cu" "F.Mask" "F.Paste")
			(net "GND")
		)
		(pad "B57" smd circle
			(at 9.752838 -26.494486 270)
			(size 0.4318 0.4318)
			(layers "F.Cu" "F.Mask" "F.Paste")
			(net "M_A_CPU0_SA_CB<4>")
		)
		(pad "B59" smd circle
			(at 11.380724 -26.494486 270)
			(size 0.4318 0.4318)
			(layers "F.Cu" "F.Mask" "F.Paste")
			(net "M_A_CPU0_SA_CB<1>")
		)
		(pad "B61" smd circle
			(at 13.008356 -26.494486 270)
			(size 0.4318 0.4318)
			(layers "F.Cu" "F.Mask" "F.Paste")
			(net "GND")
		)
		(pad "B63" smd circle
			(at 14.635988 -26.494486 270)
			(size 0.4318 0.4318)
			(layers "F.Cu" "F.Mask" "F.Paste")
			(net "M_A_CPU0_SA_DQ<28>")
		)
		(pad "B65" smd oval
			(at 16.263874 -26.494486 90)
			(size 0.381 0.4826)
			(drill
				(offset 0 -0.0508)
			)
			(layers "F.Cu" "F.Mask" "F.Paste")
			(net "M_A_CPU0_SA_DQ<25>")
		)
		(pad "B67" smd oval
			(at 17.89176 -26.494486 90)
			(size 0.381 0.4826)
			(drill
				(offset 0 -0.0508)
			)
			(layers "F.Cu" "F.Mask" "F.Paste")
			(net "GND")
		)
		(pad "B69" smd oval
			(at 19.519392 -26.494486 90)
			(size 0.381 0.4826)
			(drill
				(offset 0 -0.0508)
			)
			(layers "F.Cu" "F.Mask" "F.Paste")
			(net "M_A_CPU0_SA_DQ<20>")
		)
		(pad "B71" smd oval
			(at 21.147278 -26.494486 90)
			(size 0.381 0.4826)
			(drill
				(offset 0 -0.0508)
			)
			(layers "F.Cu" "F.Mask" "F.Paste")
			(net "M_A_CPU0_SA_DQS_DN<2>")
		)
		(pad "B73" smd oval
			(at 22.77491 -26.494486 90)
			(size 0.381 0.4826)
			(drill
				(offset 0 -0.0508)
			)
			(layers "F.Cu" "F.Mask" "F.Paste")
			(net "M_A_CPU0_SA_DQ<16>")
		)
		(pad "B75" smd oval
			(at 24.402796 -26.494486 90)
			(size 0.381 0.4826)
			(drill
				(offset 0 -0.0508)
			)
			(layers "F.Cu" "F.Mask" "F.Paste")
			(net "GND")
		)
		(pad "B77" smd oval
			(at 26.030682 -26.494486 90)
			(size 0.381 0.4826)
			(drill
				(offset 0 -0.0508)
			)
			(layers "F.Cu" "F.Mask" "F.Paste")
			(net "M_A_CPU0_SA_DQS_DN<0>")
		)
		(pad "B79" smd oval
			(at 27.658314 -26.494486 90)
			(size 0.381 0.4826)
			(drill
				(offset 0 -0.0508)
			)
			(layers "F.Cu" "F.Mask" "F.Paste")
			(net "M_A_CPU0_SA_DQ<1>")
		)
		(pad "B81" smd oval
			(at 29.2862 -26.494486 90)
			(size 0.381 0.4826)
			(drill
				(offset 0 -0.0508)
			)
			(layers "F.Cu" "F.Mask" "F.Paste")
			(net "M_A_CPU0_SA_DQ<0>")
		)
		(pad "B83" smd oval
			(at 30.914086 -26.494486 45)
			(size 0.381 0.4826)
			(drill
				(offset 0 -0.0508)
			)
			(layers "F.Cu" "F.Mask" "F.Paste")
			(net "GND")
		)
		(pad "B85" smd oval
			(at 32.541718 -26.494486 45)
			(size 0.381 0.4826)
			(drill
				(offset 0 -0.0508)
			)
			(layers "F.Cu" "F.Mask" "F.Paste")
			(net "UPI_CPU0_CPU1_P2P2_DN<23>")
		)
		(pad "B87" smd oval
			(at 34.169604 -26.494486 45)
			(size 0.381 0.4826)
			(drill
				(offset 0 -0.0508)
			)
			(layers "F.Cu" "F.Mask" "F.Paste")
			(net "GND")
		)
		(pad "BA1" smd oval
			(at -37.425122 -8.278114 180)
			(size 0.381 0.4826)
			(drill
				(offset 0 -0.0508)
			)
			(layers "F.Cu" "F.Mask" "F.Paste")
			(net "UPI_CPU0_CPU1_P0P1_DP<16>")
		)
		(pad "BA3" smd circle
			(at -35.797236 -8.278114 270)
			(size 0.4318 0.4318)
			(layers "F.Cu" "F.Mask" "F.Paste")
			(net "PVCCD_HV_CPU0")
		)
		(pad "BA5" smd circle
			(at -34.169604 -8.278114 270)
			(size 0.4318 0.4318)
			(layers "F.Cu" "F.Mask" "F.Paste")
			(net "UPI_CPU1_CPU0_P1P0_DP<15>")
		)
		(pad "BA7" smd circle
			(at -32.541718 -8.278114 270)
			(size 0.4318 0.4318)
			(layers "F.Cu" "F.Mask" "F.Paste")
			(net "PVCCD_HV_CPU0")
		)
		(pad "BA9" smd circle
			(at -30.914086 -8.278114 270)
			(size 0.4318 0.4318)
			(layers "F.Cu" "F.Mask" "F.Paste")
			(net "P5E_CPU0_PE0_RX_DN<15>")
		)
		(pad "BA11" smd circle
			(at -29.2862 -8.278114 270)
			(size 0.4318 0.4318)
			(layers "F.Cu" "F.Mask" "F.Paste")
			(net "VSENSE_PVCCFA_EHV_CPU0_DN")
		)
		(pad "BA13" smd circle
			(at -27.658314 -8.278114 270)
			(size 0.4318 0.4318)
			(layers "F.Cu" "F.Mask" "F.Paste")
			(net "P5E_CPU0_PE0_TX_DN<14>")
		)
		(pad "BA15" smd circle
			(at -26.030682 -8.278114 270)
			(size 0.4318 0.4318)
			(layers "F.Cu" "F.Mask" "F.Paste")
			(net "PVCCINFAON_CPU0")
		)
		(pad "BA17" smd circle
			(at -24.402796 -8.278114 270)
			(size 0.4318 0.4318)
			(layers "F.Cu" "F.Mask" "F.Paste")
			(net "GND")
		)
		(pad "BA19" smd circle
			(at -22.77491 -8.278114 270)
			(size 0.4318 0.4318)
			(layers "F.Cu" "F.Mask" "F.Paste")
			(net "PVNN_MAIN_CPU0")
		)
		(pad "BA21" smd circle
			(at -21.147278 -8.278114 270)
			(size 0.4318 0.4318)
			(layers "F.Cu" "F.Mask" "F.Paste")
			(net "P3V3_AUX")
		)
		(pad "BA23" smd circle
			(at -19.519392 -8.278114 270)
			(size 0.4318 0.4318)
			(layers "F.Cu" "F.Mask" "F.Paste")
			(net "PU_CPU0_UPI0_AC_COUPLING")
		)
		(pad "BA25" smd circle
			(at -17.89176 -8.278114 270)
			(size 0.4318 0.4318)
			(layers "F.Cu" "F.Mask" "F.Paste")
			(net "NC_CPU0_SOC_SPARE4")
		)
		(pad "BA60" smd circle
			(at 12.19454 -8.168132 270)
			(size 0.4318 0.4318)
			(layers "F.Cu" "F.Mask" "F.Paste")
			(net "GND")
		)
		(pad "BA62" smd circle
			(at 13.822426 -8.168132 270)
			(size 0.4318 0.4318)
			(layers "F.Cu" "F.Mask" "F.Paste")
			(net "TP_SPI_S3M_CPU0_IO0_LVC1_R")
		)
		(pad "BA64" smd circle
			(at 15.450058 -8.168132 270)
			(size 0.4318 0.4318)
			(layers "F.Cu" "F.Mask" "F.Paste")
			(net "GND")
		)
		(pad "BA66" smd circle
			(at 17.07769 -8.168132 270)
			(size 0.4318 0.4318)
			(layers "F.Cu" "F.Mask" "F.Paste")
			(net "TP_SPI_IBL_CPU0_TPM_IO0")
		)
		(pad "BA68" smd circle
			(at 18.705576 -8.168132 270)
			(size 0.4318 0.4318)
			(layers "F.Cu" "F.Mask" "F.Paste")
			(net "TP_SPI_S3M_CPU0_OE_LVC1_R_N")
		)
		(pad "BA70" smd circle
			(at 20.333462 -8.168132 270)
			(size 0.4318 0.4318)
			(layers "F.Cu" "F.Mask" "F.Paste")
			(net "FM_S3M_CPU0_LVC1_GPIO_0")
		)
		(pad "BA72" smd circle
			(at 21.961094 -8.168132 270)
			(size 0.4318 0.4318)
			(layers "F.Cu" "F.Mask" "F.Paste")
			(net "UPI_CPU1_CPU0_P2P2_DP<11>")
		)
		(pad "BA74" smd circle
			(at 23.58898 -8.168132 270)
			(size 0.4318 0.4318)
			(layers "F.Cu" "F.Mask" "F.Paste")
			(net "GND")
		)
		(pad "BA76" smd circle
			(at 25.216612 -8.168132 270)
			(size 0.4318 0.4318)
			(layers "F.Cu" "F.Mask" "F.Paste")
			(net "UPI_CPU1_CPU0_P2P2_DP<9>")
		)
	)
)
